# S9S_MB_2U (Grand Teton) — schematic netlist excerpt (pin names and nets, part order shuffled) for the footprints in the layout excerpt that follows; sources: Cadence DE-HDL packaged netlist, KiCad conversion of 03242023_DA0F0TMBIJ0_F0T_Motherboard_J_brd_V01_OCP.brd

R4504  Q_RES  0 5% CHIP  pkg 0402LF  page 183 : A = SMB_SML1_PMBUS_3V3AUX_PCH_SDA ; B = SMB_SML1_PMBUS_3V3AUX_PCH_SDA_1
PC515_P1_6  Q_CAP  22UF 16V 20% X6S  pkg C0805  page 287 : A = SW_P12V_PVCCIN_CPU1_FLT ; B = GND
PR290  Q_RES  0 5% CHIP  pkg 0402LF  page 288 : A = PVCCIN_CPU1_VOS7 ; B = PVCCIN_CPU1

(kicad_pcb
	(version 20260206)
	(generator "pcbnew")
	(generator_version "10.0")
	(general
		(thickness 1.6)
		(legacy_teardrops no)
	)
	(paper "A4")
	(title_block
		(title "03242023_DA0F0TMBIJ0_F0T_Motherboard_J_brd_V01_OCP.brd")
		(comment 1 "Grand Teton / footprints 4388-4390 of 6105")
	)
	(layers
		(0 "F.Cu" signal "TOP")
		(4 "In1.Cu" signal "GND")
		(6 "In2.Cu" signal "IN1")
		(8 "In3.Cu" signal "GND1")
		(10 "In4.Cu" signal "IN2")
		(12 "In5.Cu" signal "GND2")
		(14 "In6.Cu" signal "IN3")
		(16 "In7.Cu" signal "GND3")
		(18 "In8.Cu" signal "VCC")
		(20 "In9.Cu" signal "VCC1")
		(22 "In10.Cu" signal "GND4")
		(24 "In11.Cu" signal "IN4")
		(26 "In12.Cu" signal "GND5")
		(28 "In13.Cu" signal "IN5")
		(30 "In14.Cu" signal "GND6")
		(32 "In15.Cu" signal "IN6")
		(34 "In16.Cu" signal "GND7")
		(2 "B.Cu" signal "BOTTOM")
		(9 "F.Adhes" user "F.Adhesive")
		(11 "B.Adhes" user "B.Adhesive")
		(13 "F.Paste" user "Package Geometry/Pastemask Top")
		(15 "B.Paste" user "Package Geometry/Pastemask Bottom")
		(5 "F.SilkS" user "Ref Des/Silkscreen Top")
		(7 "B.SilkS" user "Ref Des/Silkscreen Bottom")
		(1 "F.Mask" user "Board Geometry/Soldermask Top")
		(3 "B.Mask" user "Board Geometry/Soldermask Bottom")
		(17 "Dwgs.User" user "User.Drawings")
		(19 "Cmts.User" user "User.Comments")
		(21 "Eco1.User" user "User.Eco1")
		(23 "Eco2.User" user "User.Eco2")
		(25 "Edge.Cuts" user "Board Geometry/Outline")
		(27 "Margin" user)
		(31 "F.CrtYd" user "Package Geometry/Place Bound Top")
		(29 "B.CrtYd" user "Package Geometry/Place Bound Bottom")
		(35 "F.Fab" user "Ref Des/Assembly Top")
		(33 "B.Fab" user "Ref Des/Assembly Bottom")
	)
	(footprint ""
		(layer "B.Cu")
		(at 89.958926 -337.145884 90)
		(property "Reference" "PC515_P1_6"
			(at 0 0 90)
			(layer "B.SilkS")
			(hide yes)
			(effects
				(font
					(size 1.27 1.27)
				)
				(justify mirror)
			)
		)
		(property "Value" ""
			(at 0 0 90)
			(layer "B.Fab")
			(effects
				(font
					(size 1.27 1.27)
				)
				(justify mirror)
			)
		)
		(duplicate_pad_numbers_are_jumpers no)
		(fp_line
			(start 1.524 -0.762)
			(end -1.524 -0.762)
			(stroke
				(width 0.1524)
				(type default)
			)
			(layer "B.SilkS")
		)
		(fp_line
			(start -1.524 -0.762)
			(end -1.524 0.762)
			(stroke
				(width 0.1524)
				(type default)
			)
			(layer "B.SilkS")
		)
		(fp_line
			(start 1.524 0.762)
			(end 1.524 -0.762)
			(stroke
				(width 0.1524)
				(type default)
			)
			(layer "B.SilkS")
		)
		(fp_line
			(start -1.524 0.762)
			(end 1.524 0.762)
			(stroke
				(width 0.1524)
				(type default)
			)
			(layer "B.SilkS")
		)
		(fp_line
			(start 1.1049 -0.724916)
			(end 1.1049 0.724916)
			(stroke
				(width 0.1)
				(type default)
			)
			(layer "B.Fab")
		)
		(fp_line
			(start -1.1049 -0.724916)
			(end 1.1049 -0.724916)
			(stroke
				(width 0.1)
				(type default)
			)
			(layer "B.Fab")
		)
		(fp_line
			(start 1.1049 0.724916)
			(end -1.1049 0.724916)
			(stroke
				(width 0.1)
				(type default)
			)
			(layer "B.Fab")
		)
		(fp_line
			(start -1.1049 0.724916)
			(end -1.1049 -0.724916)
			(stroke
				(width 0.1)
				(type default)
			)
			(layer "B.Fab")
		)
		(pad "1" smd rect
			(at 0.889 0 90)
			(size 1.016 1.27)
			(layers "B.Cu" "B.Mask" "B.Paste")
			(net "SW_P12V_PVCCIN_CPU1_FLT")
		)
		(pad "2" smd rect
			(at -0.889 0 90)
			(size 1.016 1.27)
			(layers "B.Cu" "B.Mask" "B.Paste")
			(net "GND")
		)
	)
	(footprint ""
		(layer "B.Cu")
		(at 76.809854 -345.830144 -90)
		(property "Reference" "PR290"
			(at 0 0 90)
			(layer "B.SilkS")
			(hide yes)
			(effects
				(font
					(size 1.27 1.27)
				)
				(justify mirror)
			)
		)
		(property "Value" ""
			(at 0 0 90)
			(layer "B.Fab")
			(effects
				(font
					(size 1.27 1.27)
				)
				(justify mirror)
			)
		)
		(duplicate_pad_numbers_are_jumpers no)
		(fp_line
			(start -0.7874 0.4064)
			(end 0.7874 0.4064)
			(stroke
				(width 0.1524)
				(type default)
			)
			(layer "B.SilkS")
		)
		(fp_line
			(start 0.7874 0.4064)
			(end 0.7874 -0.4064)
			(stroke
				(width 0.1524)
				(type default)
			)
			(layer "B.SilkS")
		)
		(fp_line
			(start -0.7874 -0.4064)
			(end -0.7874 0.4064)
			(stroke
				(width 0.1524)
				(type default)
			)
			(layer "B.SilkS")
		)
		(fp_line
			(start 0.7874 -0.4064)
			(end -0.7874 -0.4064)
			(stroke
				(width 0.1524)
				(type default)
			)
			(layer "B.SilkS")
		)
		(fp_line
			(start -0.67945 0.3048)
			(end -0.120396 0.3048)
			(stroke
				(width 0.1)
				(type default)
			)
			(layer "B.Fab")
		)
		(fp_line
			(start -0.120396 0.3048)
			(end -0.120396 0.2794)
			(stroke
				(width 0.1)
				(type default)
			)
			(layer "B.Fab")
		)
		(fp_line
			(start 0.12065 0.3048)
			(end 0.67945 0.3048)
			(stroke
				(width 0.1)
				(type default)
			)
			(layer "B.Fab")
		)
		(fp_line
			(start 0.67945 0.3048)
			(end 0.67945 -0.305054)
			(stroke
				(width 0.1)
				(type default)
			)
			(layer "B.Fab")
		)
		(fp_line
			(start -0.120396 0.2794)
			(end 0.12065 0.2794)
			(stroke
				(width 0.1)
				(type default)
			)
			(layer "B.Fab")
		)
		(fp_line
			(start 0.12065 0.2794)
			(end 0.12065 0.3048)
			(stroke
				(width 0.1)
				(type default)
			)
			(layer "B.Fab")
		)
		(fp_line
			(start -0.12065 -0.2794)
			(end -0.12065 -0.3048)
			(stroke
				(width 0.1)
				(type default)
			)
			(layer "B.Fab")
		)
		(fp_line
			(start 0.12065 -0.2794)
			(end -0.12065 -0.2794)
			(stroke
				(width 0.1)
				(type default)
			)
			(layer "B.Fab")
		)
		(fp_line
			(start -0.67945 -0.3048)
			(end -0.67945 0.3048)
			(stroke
				(width 0.1)
				(type default)
			)
			(layer "B.Fab")
		)
		(fp_line
			(start -0.12065 -0.3048)
			(end -0.67945 -0.3048)
			(stroke
				(width 0.1)
				(type default)
			)
			(layer "B.Fab")
		)
		(fp_line
			(start 0.12065 -0.305054)
			(end 0.12065 -0.2794)
			(stroke
				(width 0.1)
				(type default)
			)
			(layer "B.Fab")
		)
		(fp_line
			(start 0.67945 -0.305054)
			(end 0.12065 -0.305054)
			(stroke
				(width 0.1)
				(type default)
			)
			(layer "B.Fab")
		)
		(pad "1" smd circle
			(at 0.40005 0 90)
			(size 0 0)
			(layers "B.Cu" "B.Mask" "B.Paste")
			(net "PVCCIN_CPU1_VOS7")
		)
		(pad "2" smd circle
			(at -0.40005 0 90)
			(size 0 0)
			(layers "B.Cu" "B.Mask" "B.Paste")
			(net "PVCCIN_CPU1")
		)
	)
	(footprint ""
		(layer "B.Cu")
		(at 178.689 -19.522948 -90)
		(property "Reference" "R4504"
			(at 0 0 90)
			(layer "B.SilkS")
			(hide yes)
			(effects
				(font
					(size 1.27 1.27)
				)
				(justify mirror)
			)
		)
		(property "Value" ""
			(at 0 0 90)
			(layer "B.Fab")
			(effects
				(font
					(size 1.27 1.27)
				)
				(justify mirror)
			)
		)
		(duplicate_pad_numbers_are_jumpers no)
		(fp_line
			(start -0.7874 0.4064)
			(end 0.7874 0.4064)
			(stroke
				(width 0.1524)
				(type default)
			)
			(layer "B.SilkS")
		)
		(fp_line
			(start 0.7874 0.4064)
			(end 0.7874 -0.4064)
			(stroke
				(width 0.1524)
				(type default)
			)
			(layer "B.SilkS")
		)
		(fp_line
			(start -0.7874 -0.4064)
			(end -0.7874 0.4064)
			(stroke
				(width 0.1524)
				(type default)
			)
			(layer "B.SilkS")
		)
		(fp_line
			(start 0.7874 -0.4064)
			(end -0.7874 -0.4064)
			(stroke
				(width 0.1524)
				(type default)
			)
			(layer "B.SilkS")
		)
		(fp_line
			(start -0.67945 0.3048)
			(end -0.120396 0.3048)
			(stroke
				(width 0.1)
				(type default)
			)
			(layer "B.Fab")
		)
		(fp_line
			(start -0.120396 0.3048)
			(end -0.120396 0.2794)
			(stroke
				(width 0.1)
				(type default)
			)
			(layer "B.Fab")
		)
		(fp_line
			(start 0.12065 0.3048)
			(end 0.67945 0.3048)
			(stroke
				(width 0.1)
				(type default)
			)
			(layer "B.Fab")
		)
		(fp_line
			(start 0.67945 0.3048)
			(end 0.67945 -0.305054)
			(stroke
				(width 0.1)
				(type default)
			)
			(layer "B.Fab")
		)
		(fp_line
			(start -0.120396 0.2794)
			(end 0.12065 0.2794)
			(stroke
				(width 0.1)
				(type default)
			)
			(layer "B.Fab")
		)
		(fp_line
			(start 0.12065 0.2794)
			(end 0.12065 0.3048)
			(stroke
				(width 0.1)
				(type default)
			)
			(layer "B.Fab")
		)
		(fp_line
			(start -0.12065 -0.2794)
			(end -0.12065 -0.3048)
			(stroke
				(width 0.1)
				(type default)
			)
			(layer "B.Fab")
		)
		(fp_line
			(start 0.12065 -0.2794)
			(end -0.12065 -0.2794)
			(stroke
				(width 0.1)
				(type default)
			)
			(layer "B.Fab")
		)
		(fp_line
			(start -0.67945 -0.3048)
			(end -0.67945 0.3048)
			(stroke
				(width 0.1)
				(type default)
			)
			(layer "B.Fab")
		)
		(fp_line
			(start -0.12065 -0.3048)
			(end -0.67945 -0.3048)
			(stroke
				(width 0.1)
				(type default)
			)
			(layer "B.Fab")
		)
		(fp_line
			(start 0.12065 -0.305054)
			(end 0.12065 -0.2794)
			(stroke
				(width 0.1)
				(type default)
			)
			(layer "B.Fab")
		)
		(fp_line
			(start 0.67945 -0.305054)
			(end 0.12065 -0.305054)
			(stroke
				(width 0.1)
				(type default)
			)
			(layer "B.Fab")
		)
		(pad "1" smd circle
			(at 0.40005 0 90)
			(size 0 0)
			(layers "B.Cu" "B.Mask" "B.Paste")
			(net "SMB_SML1_PMBUS_3V3AUX_PCH_SDA")
		)
		(pad "2" smd circle
			(at -0.40005 0 90)
			(size 0 0)
			(layers "B.Cu" "B.Mask" "B.Paste")
			(net "SMB_SML1_PMBUS_3V3AUX_PCH_SDA_1")
		)
	)
)
